# T6G (Grand Teton) — schematic netlist excerpt (pin names and nets, part order shuffled) for the footprints in the layout excerpt that follows; sources: Cadence DE-HDL packaged netlist, KiCad conversion of 04192023_DAF0TMB3IC0_F0TG_MB_C_brd_V02_OCP.brd

C414  Q_CAP  10UF 6.3V 20% X6S  pkg C0402  page 345 : A = P0V9_CPU1_RT_2D ; B = GND
R274  Q_RES  0 5% CHIP  pkg 0402LF  page 160 : A = SMB_CPU0_CPU1_APML_BUF2_SCL_R2 ; B = SMB_CPU0_CPU1_APML_SCL_R2

(kicad_pcb
	(version 20260206)
	(generator "pcbnew")
	(generator_version "10.0")
	(general
		(thickness 1.6)
		(legacy_teardrops no)
	)
	(paper "A4")
	(title_block
		(title "04192023_DAF0TMB3IC0_F0TG_MB_C_brd_V02_OCP.brd")
		(comment 1 "Grand Teton / footprints 6711-6712 of 8354")
	)
	(layers
		(0 "F.Cu" signal "TOP")
		(4 "In1.Cu" signal "GND")
		(6 "In2.Cu" signal "IN1")
		(8 "In3.Cu" signal "GND1")
		(10 "In4.Cu" signal "IN2")
		(12 "In5.Cu" signal "GND2")
		(14 "In6.Cu" signal "IN3")
		(16 "In7.Cu" signal "GND3")
		(18 "In8.Cu" signal "VCC")
		(20 "In9.Cu" signal "VCC1")
		(22 "In10.Cu" signal "GND4")
		(24 "In11.Cu" signal "IN4")
		(26 "In12.Cu" signal "GND5")
		(28 "In13.Cu" signal "IN5")
		(30 "In14.Cu" signal "GND6")
		(32 "In15.Cu" signal "IN6")
		(34 "In16.Cu" signal "GND7")
		(2 "B.Cu" signal "BOTTOM")
		(9 "F.Adhes" user "F.Adhesive")
		(11 "B.Adhes" user "B.Adhesive")
		(13 "F.Paste" user "Package Geometry/Pastemask Top")
		(15 "B.Paste" user "Package Geometry/Pastemask Bottom")
		(5 "F.SilkS" user "Ref Des/Silkscreen Top")
		(7 "B.SilkS" user "Ref Des/Silkscreen Bottom")
		(1 "F.Mask" user "Board Geometry/Soldermask Top")
		(3 "B.Mask" user "Board Geometry/Soldermask Bottom")
		(17 "Dwgs.User" user "User.Drawings")
		(19 "Cmts.User" user "User.Comments")
		(21 "Eco1.User" user "User.Eco1")
		(23 "Eco2.User" user "User.Eco2")
		(25 "Edge.Cuts" user "Board Geometry/Outline")
		(27 "Margin" user)
		(31 "F.CrtYd" user "Package Geometry/Place Bound Top")
		(29 "B.CrtYd" user "Package Geometry/Place Bound Bottom")
		(35 "F.Fab" user "Ref Des/Assembly Top")
		(33 "B.Fab" user "Ref Des/Assembly Bottom")
	)
	(footprint ""
		(layer "B.Cu")
		(at 154.218894 -390.560052 90)
		(property "Reference" "C414"
			(at 0 0 90)
			(layer "B.SilkS")
			(hide yes)
			(effects
				(font
					(size 1.27 1.27)
				)
				(justify mirror)
			)
		)
		(property "Value" ""
			(at 0 0 90)
			(layer "B.Fab")
			(effects
				(font
					(size 1.27 1.27)
				)
				(justify mirror)
			)
		)
		(duplicate_pad_numbers_are_jumpers no)
		(fp_line
			(start 0.7874 -0.4064)
			(end -0.7874 -0.4064)
			(stroke
				(width 0.1524)
				(type default)
			)
			(layer "B.SilkS")
		)
		(fp_line
			(start -0.7874 -0.4064)
			(end -0.7874 0.4064)
			(stroke
				(width 0.1524)
				(type default)
			)
			(layer "B.SilkS")
		)
		(fp_line
			(start 0.7874 0.4064)
			(end 0.7874 -0.4064)
			(stroke
				(width 0.1524)
				(type default)
			)
			(layer "B.SilkS")
		)
		(fp_line
			(start -0.7874 0.4064)
			(end 0.7874 0.4064)
			(stroke
				(width 0.1524)
				(type default)
			)
			(layer "B.SilkS")
		)
		(fp_line
			(start 0.67945 -0.305054)
			(end 0.12065 -0.305054)
			(stroke
				(width 0.1)
				(type default)
			)
			(layer "B.Fab")
		)
		(fp_line
			(start 0.12065 -0.305054)
			(end 0.12065 -0.2794)
			(stroke
				(width 0.1)
				(type default)
			)
			(layer "B.Fab")
		)
		(fp_line
			(start -0.12065 -0.3048)
			(end -0.67945 -0.3048)
			(stroke
				(width 0.1)
				(type default)
			)
			(layer "B.Fab")
		)
		(fp_line
			(start -0.67945 -0.3048)
			(end -0.67945 0.3048)
			(stroke
				(width 0.1)
				(type default)
			)
			(layer "B.Fab")
		)
		(fp_line
			(start 0.12065 -0.2794)
			(end -0.12065 -0.2794)
			(stroke
				(width 0.1)
				(type default)
			)
			(layer "B.Fab")
		)
		(fp_line
			(start -0.12065 -0.2794)
			(end -0.12065 -0.3048)
			(stroke
				(width 0.1)
				(type default)
			)
			(layer "B.Fab")
		)
		(fp_line
			(start 0.12065 0.2794)
			(end 0.12065 0.3048)
			(stroke
				(width 0.1)
				(type default)
			)
			(layer "B.Fab")
		)
		(fp_line
			(start -0.120396 0.2794)
			(end 0.12065 0.2794)
			(stroke
				(width 0.1)
				(type default)
			)
			(layer "B.Fab")
		)
		(fp_line
			(start 0.67945 0.3048)
			(end 0.67945 -0.305054)
			(stroke
				(width 0.1)
				(type default)
			)
			(layer "B.Fab")
		)
		(fp_line
			(start 0.12065 0.3048)
			(end 0.67945 0.3048)
			(stroke
				(width 0.1)
				(type default)
			)
			(layer "B.Fab")
		)
		(fp_line
			(start -0.120396 0.3048)
			(end -0.120396 0.2794)
			(stroke
				(width 0.1)
				(type default)
			)
			(layer "B.Fab")
		)
		(fp_line
			(start -0.67945 0.3048)
			(end -0.120396 0.3048)
			(stroke
				(width 0.1)
				(type default)
			)
			(layer "B.Fab")
		)
		(pad "1" smd circle
			(at 0.40005 0 270)
			(size 0 0)
			(layers "B.Cu" "B.Mask" "B.Paste")
			(net "P0V9_CPU1_RT_2D")
		)
		(pad "2" smd circle
			(at -0.40005 0 270)
			(size 0 0)
			(layers "B.Cu" "B.Mask" "B.Paste")
			(net "GND")
		)
	)
	(footprint ""
		(layer "B.Cu")
		(at 234.315 -215.186514 180)
		(property "Reference" "R274"
			(at 0 0 0)
			(layer "B.SilkS")
			(hide yes)
			(effects
				(font
					(size 1.27 1.27)
				)
				(justify mirror)
			)
		)
		(property "Value" ""
			(at 0 0 0)
			(layer "B.Fab")
			(effects
				(font
					(size 1.27 1.27)
				)
				(justify mirror)
			)
		)
		(duplicate_pad_numbers_are_jumpers no)
		(fp_line
			(start 0.7874 0.4064)
			(end 0.7874 -0.4064)
			(stroke
				(width 0.1524)
				(type default)
			)
			(layer "B.SilkS")
		)
		(fp_line
			(start 0.7874 -0.4064)
			(end -0.7874 -0.4064)
			(stroke
				(width 0.1524)
				(type default)
			)
			(layer "B.SilkS")
		)
		(fp_line
			(start -0.7874 0.4064)
			(end 0.7874 0.4064)
			(stroke
				(width 0.1524)
				(type default)
			)
			(layer "B.SilkS")
		)
		(fp_line
			(start -0.7874 -0.4064)
			(end -0.7874 0.4064)
			(stroke
				(width 0.1524)
				(type default)
			)
			(layer "B.SilkS")
		)
		(fp_line
			(start 0.67945 0.3048)
			(end 0.67945 -0.305054)
			(stroke
				(width 0.1)
				(type default)
			)
			(layer "B.Fab")
		)
		(fp_line
			(start 0.67945 -0.305054)
			(end 0.12065 -0.305054)
			(stroke
				(width 0.1)
				(type default)
			)
			(layer "B.Fab")
		)
		(fp_line
			(start 0.12065 0.3048)
			(end 0.67945 0.3048)
			(stroke
				(width 0.1)
				(type default)
			)
			(layer "B.Fab")
		)
		(fp_line
			(start 0.12065 0.2794)
			(end 0.12065 0.3048)
			(stroke
				(width 0.1)
				(type default)
			)
			(layer "B.Fab")
		)
		(fp_line
			(start 0.12065 -0.2794)
			(end -0.12065 -0.2794)
			(stroke
				(width 0.1)
				(type default)
			)
			(layer "B.Fab")
		)
		(fp_line
			(start 0.12065 -0.305054)
			(end 0.12065 -0.2794)
			(stroke
				(width 0.1)
				(type default)
			)
			(layer "B.Fab")
		)
		(fp_line
			(start -0.120396 0.3048)
			(end -0.120396 0.2794)
			(stroke
				(width 0.1)
				(type default)
			)
			(layer "B.Fab")
		)
		(fp_line
			(start -0.120396 0.2794)
			(end 0.12065 0.2794)
			(stroke
				(width 0.1)
				(type default)
			)
			(layer "B.Fab")
		)
		(fp_line
			(start -0.12065 -0.2794)
			(end -0.12065 -0.3048)
			(stroke
				(width 0.1)
				(type default)
			)
			(layer "B.Fab")
		)
		(fp_line
			(start -0.12065 -0.3048)
			(end -0.67945 -0.3048)
			(stroke
				(width 0.1)
				(type default)
			)
			(layer "B.Fab")
		)
		(fp_line
			(start -0.67945 0.3048)
			(end -0.120396 0.3048)
			(stroke
				(width 0.1)
				(type default)
			)
			(layer "B.Fab")
		)
		(fp_line
			(start -0.67945 -0.3048)
			(end -0.67945 0.3048)
			(stroke
				(width 0.1)
				(type default)
			)
			(layer "B.Fab")
		)
		(pad "1" smd rect
			(at 0.40005 0 180)
			(size 0.4572 0.508)
			(layers "B.Cu" "B.Mask" "B.Paste")
			(net "SMB_CPU0_CPU1_APML_BUF2_SCL_R2")
		)
		(pad "2" smd rect
			(at -0.40005 0 180)
			(size 0.4572 0.508)
			(layers "B.Cu" "B.Mask" "B.Paste")
			(net "SMB_CPU0_CPU1_APML_SCL_R2")
		)
	)
)
